# S9S_MB_2U (Grand Teton) — schematic netlist excerpt (pin names and nets, part order shuffled) for the footprints in the layout excerpt that follows; sources: Cadence DE-HDL packaged netlist, KiCad conversion of 03242023_DA0F0TMBIJ0_F0T_Motherboard_J_brd_V01_OCP.brd

C2373  Q_CAP  1000PF 50V 5% EMPTY  pkg 0402  page 144 : A = PRSNT_CABLE_SWB_B2_ISO_N ; B = GND
R3923  Q_RES  63.4K 1% CHIP  pkg 0402LF  page 301 : A = P12V_PSU_FUSE ; B = PDB_PRSNT_N

(kicad_pcb
	(version 20260206)
	(generator "pcbnew")
	(generator_version "10.0")
	(general
		(thickness 1.6)
		(legacy_teardrops no)
	)
	(paper "A4")
	(title_block
		(title "03242023_DA0F0TMBIJ0_F0T_Motherboard_J_brd_V01_OCP.brd")
		(comment 1 "Grand Teton / footprints 4120-4121 of 6105")
	)
	(layers
		(0 "F.Cu" signal "TOP")
		(4 "In1.Cu" signal "GND")
		(6 "In2.Cu" signal "IN1")
		(8 "In3.Cu" signal "GND1")
		(10 "In4.Cu" signal "IN2")
		(12 "In5.Cu" signal "GND2")
		(14 "In6.Cu" signal "IN3")
		(16 "In7.Cu" signal "GND3")
		(18 "In8.Cu" signal "VCC")
		(20 "In9.Cu" signal "VCC1")
		(22 "In10.Cu" signal "GND4")
		(24 "In11.Cu" signal "IN4")
		(26 "In12.Cu" signal "GND5")
		(28 "In13.Cu" signal "IN5")
		(30 "In14.Cu" signal "GND6")
		(32 "In15.Cu" signal "IN6")
		(34 "In16.Cu" signal "GND7")
		(2 "B.Cu" signal "BOTTOM")
		(9 "F.Adhes" user "F.Adhesive")
		(11 "B.Adhes" user "B.Adhesive")
		(13 "F.Paste" user "Package Geometry/Pastemask Top")
		(15 "B.Paste" user "Package Geometry/Pastemask Bottom")
		(5 "F.SilkS" user "Ref Des/Silkscreen Top")
		(7 "B.SilkS" user "Ref Des/Silkscreen Bottom")
		(1 "F.Mask" user "Board Geometry/Soldermask Top")
		(3 "B.Mask" user "Board Geometry/Soldermask Bottom")
		(17 "Dwgs.User" user "User.Drawings")
		(19 "Cmts.User" user "User.Comments")
		(21 "Eco1.User" user "User.Eco1")
		(23 "Eco2.User" user "User.Eco2")
		(25 "Edge.Cuts" user "Board Geometry/Outline")
		(27 "Margin" user)
		(31 "F.CrtYd" user "Package Geometry/Place Bound Top")
		(29 "B.CrtYd" user "Package Geometry/Place Bound Bottom")
		(35 "F.Fab" user "Ref Des/Assembly Top")
		(33 "B.Fab" user "Ref Des/Assembly Bottom")
	)
	(footprint ""
		(layer "F.Cu")
		(at 189.65037 -425.287948)
		(property "Reference" "R3923"
			(at 0 0 0)
			(layer "F.SilkS")
			(hide yes)
			(effects
				(font
					(size 1.27 1.27)
				)
			)
		)
		(property "Value" ""
			(at 0 0 0)
			(layer "F.Fab")
			(effects
				(font
					(size 1.27 1.27)
				)
			)
		)
		(duplicate_pad_numbers_are_jumpers no)
		(fp_line
			(start -0.7874 -0.4064)
			(end 0.7874 -0.4064)
			(stroke
				(width 0.1524)
				(type default)
			)
			(layer "F.SilkS")
		)
		(fp_line
			(start -0.7874 0.4064)
			(end -0.7874 -0.4064)
			(stroke
				(width 0.1524)
				(type default)
			)
			(layer "F.SilkS")
		)
		(fp_line
			(start 0.7874 -0.4064)
			(end 0.7874 0.4064)
			(stroke
				(width 0.1524)
				(type default)
			)
			(layer "F.SilkS")
		)
		(fp_line
			(start 0.7874 0.4064)
			(end -0.7874 0.4064)
			(stroke
				(width 0.1524)
				(type default)
			)
			(layer "F.SilkS")
		)
		(fp_line
			(start -0.67945 -0.305054)
			(end -0.12065 -0.305054)
			(stroke
				(width 0.1)
				(type default)
			)
			(layer "F.Fab")
		)
		(fp_line
			(start -0.67945 0.3048)
			(end -0.67945 -0.305054)
			(stroke
				(width 0.1)
				(type default)
			)
			(layer "F.Fab")
		)
		(fp_line
			(start -0.12065 -0.305054)
			(end -0.12065 -0.2794)
			(stroke
				(width 0.1)
				(type default)
			)
			(layer "F.Fab")
		)
		(fp_line
			(start -0.12065 -0.2794)
			(end 0.12065 -0.2794)
			(stroke
				(width 0.1)
				(type default)
			)
			(layer "F.Fab")
		)
		(fp_line
			(start -0.12065 0.2794)
			(end -0.12065 0.3048)
			(stroke
				(width 0.1)
				(type default)
			)
			(layer "F.Fab")
		)
		(fp_line
			(start -0.12065 0.3048)
			(end -0.67945 0.3048)
			(stroke
				(width 0.1)
				(type default)
			)
			(layer "F.Fab")
		)
		(fp_line
			(start 0.120396 0.2794)
			(end -0.12065 0.2794)
			(stroke
				(width 0.1)
				(type default)
			)
			(layer "F.Fab")
		)
		(fp_line
			(start 0.120396 0.3048)
			(end 0.120396 0.2794)
			(stroke
				(width 0.1)
				(type default)
			)
			(layer "F.Fab")
		)
		(fp_line
			(start 0.12065 -0.3048)
			(end 0.67945 -0.3048)
			(stroke
				(width 0.1)
				(type default)
			)
			(layer "F.Fab")
		)
		(fp_line
			(start 0.12065 -0.2794)
			(end 0.12065 -0.3048)
			(stroke
				(width 0.1)
				(type default)
			)
			(layer "F.Fab")
		)
		(fp_line
			(start 0.67945 -0.3048)
			(end 0.67945 0.3048)
			(stroke
				(width 0.1)
				(type default)
			)
			(layer "F.Fab")
		)
		(fp_line
			(start 0.67945 0.3048)
			(end 0.120396 0.3048)
			(stroke
				(width 0.1)
				(type default)
			)
			(layer "F.Fab")
		)
		(pad "1" smd circle
			(at -0.40005 0)
			(size 0 0)
			(layers "F.Cu" "F.Mask" "F.Paste")
			(net "P12V_PSU_FUSE")
		)
		(pad "2" smd circle
			(at 0.40005 0)
			(size 0 0)
			(layers "F.Cu" "F.Mask" "F.Paste")
			(net "PDB_PRSNT_N")
		)
	)
	(footprint ""
		(layer "F.Cu")
		(at 355.8286 -401.955 180)
		(property "Reference" "C2373"
			(at 0 0 180)
			(layer "F.SilkS")
			(hide yes)
			(effects
				(font
					(size 1.27 1.27)
				)
			)
		)
		(property "Value" ""
			(at 0 0 180)
			(layer "F.Fab")
			(effects
				(font
					(size 1.27 1.27)
				)
			)
		)
		(duplicate_pad_numbers_are_jumpers no)
		(fp_line
			(start 0.7874 0.4064)
			(end -0.7874 0.4064)
			(stroke
				(width 0.1524)
				(type default)
			)
			(layer "F.SilkS")
		)
		(fp_line
			(start 0.7874 -0.4064)
			(end 0.7874 0.4064)
			(stroke
				(width 0.1524)
				(type default)
			)
			(layer "F.SilkS")
		)
		(fp_line
			(start -0.7874 0.4064)
			(end -0.7874 -0.4064)
			(stroke
				(width 0.1524)
				(type default)
			)
			(layer "F.SilkS")
		)
		(fp_line
			(start -0.7874 -0.4064)
			(end 0.7874 -0.4064)
			(stroke
				(width 0.1524)
				(type default)
			)
			(layer "F.SilkS")
		)
		(fp_line
			(start 0.67945 0.3048)
			(end 0.120396 0.3048)
			(stroke
				(width 0.1)
				(type default)
			)
			(layer "F.Fab")
		)
		(fp_line
			(start 0.67945 -0.3048)
			(end 0.67945 0.3048)
			(stroke
				(width 0.1)
				(type default)
			)
			(layer "F.Fab")
		)
		(fp_line
			(start 0.12065 -0.2794)
			(end 0.12065 -0.3048)
			(stroke
				(width 0.1)
				(type default)
			)
			(layer "F.Fab")
		)
		(fp_line
			(start 0.12065 -0.3048)
			(end 0.67945 -0.3048)
			(stroke
				(width 0.1)
				(type default)
			)
			(layer "F.Fab")
		)
		(fp_line
			(start 0.120396 0.3048)
			(end 0.120396 0.2794)
			(stroke
				(width 0.1)
				(type default)
			)
			(layer "F.Fab")
		)
		(fp_line
			(start 0.120396 0.2794)
			(end -0.12065 0.2794)
			(stroke
				(width 0.1)
				(type default)
			)
			(layer "F.Fab")
		)
		(fp_line
			(start -0.12065 0.3048)
			(end -0.67945 0.3048)
			(stroke
				(width 0.1)
				(type default)
			)
			(layer "F.Fab")
		)
		(fp_line
			(start -0.12065 0.2794)
			(end -0.12065 0.3048)
			(stroke
				(width 0.1)
				(type default)
			)
			(layer "F.Fab")
		)
		(fp_line
			(start -0.12065 -0.2794)
			(end 0.12065 -0.2794)
			(stroke
				(width 0.1)
				(type default)
			)
			(layer "F.Fab")
		)
		(fp_line
			(start -0.12065 -0.305054)
			(end -0.12065 -0.2794)
			(stroke
				(width 0.1)
				(type default)
			)
			(layer "F.Fab")
		)
		(fp_line
			(start -0.67945 0.3048)
			(end -0.67945 -0.305054)
			(stroke
				(width 0.1)
				(type default)
			)
			(layer "F.Fab")
		)
		(fp_line
			(start -0.67945 -0.305054)
			(end -0.12065 -0.305054)
			(stroke
				(width 0.1)
				(type default)
			)
			(layer "F.Fab")
		)
		(pad "1" smd circle
			(at -0.40005 0 180)
			(size 0 0)
			(layers "F.Cu" "F.Mask" "F.Paste")
			(net "PRSNT_CABLE_SWB_B2_ISO_N")
		)
		(pad "2" smd circle
			(at 0.40005 0 180)
			(size 0 0)
			(layers "F.Cu" "F.Mask" "F.Paste")
			(net "GND")
		)
	)
)
